(kicad_pcb
	(version 20221018)
	(generator pcbnew)
	(general
    (thickness 1.518)
  )
	(paper "A4")
	(title_block
    (title "Kria K26 Devboard")
    (date "2024-03-26")
    (rev "1.2.5")
    (comment 1 "www.antmicro.com")
    (comment 2 "Antmicro Ltd.")
		(comment 9 "footprints 428-436 of 660")
	)
	(layers
    (0 "F.Cu" mixed)
    (1 "In1.Cu" power)
    (2 "In2.Cu" mixed)
    (3 "In3.Cu" power)
    (4 "In4.Cu" mixed)
    (5 "In5.Cu" power)
    (6 "In6.Cu" mixed)
    (31 "B.Cu" power)
    (32 "B.Adhes" user "B.Adhesive")
    (33 "F.Adhes" user "F.Adhesive")
    (34 "B.Paste" user)
    (35 "F.Paste" user)
    (36 "B.SilkS" user "B.Silkscreen")
    (37 "F.SilkS" user "F.Silkscreen")
    (38 "B.Mask" user)
    (39 "F.Mask" user)
    (40 "Dwgs.User" user "User.Drawings")
    (41 "Cmts.User" user "User.Comments")
    (42 "Eco1.User" user "User.Eco1")
    (43 "Eco2.User" user "User.Eco2")
    (44 "Edge.Cuts" user)
    (45 "Margin" user)
    (46 "B.CrtYd" user "B.Courtyard")
    (47 "F.CrtYd" user "F.Courtyard")
    (48 "B.Fab" user)
    (49 "F.Fab" user)
  )
	(footprint "kria-k26-devboard-footprints:C_0402_1005Metric" (layer "B.Cu")
    (at 122.749 99.004 180)
    (descr "Capacitor SMD 0402")
    (tags "capacitor SMD 0402")
    (property "Author" "Antmicro")
    (property "Dielectric" "X5R")
    (property "License" "Apache-2.0")
    (property "MPN" "GRM155R61H104KE14D")
    (property "Manufacturer" "Murata")
    (property "Sheetfile" "usb.kicad_sch")
    (property "Sheetname" "USB")
    (property "Val" "100n")
    (property "Voltage" "50V")
    (property "ki_description" " ")
    (attr smd)
    (fp_text reference "C83" (at -1.521 0.594) (layer "B.SilkS")
        (effects (font (size 0.7 0.7) (thickness 0.15)) (justify left bottom mirror))
    )
    (fp_text value "C_100n_0402" (at 0 -1.4) (layer "B.Fab") hide
        (effects (font (size 0.7 0.7) (thickness 0.15)) (justify left bottom mirror))
    )
    (fp_text user "License: Apache-2.0" (at -0.932 -5.17) (layer "B.Fab") hide
        (effects (font (size 0.7 0.7) (thickness 0.15)) (justify left bottom mirror))
    )
    (fp_text user "${REFERENCE}" (at -0.932 -3.168) (layer "B.Fab") hide
        (effects (font (size 0.7 0.7) (thickness 0.15)) (justify left bottom mirror))
    )
    (fp_text user "Author: Antmicro" (at -0.932 -4.17) (layer "B.Fab") hide
        (effects (font (size 0.7 0.7) (thickness 0.15)) (justify left bottom mirror))
    )
    (fp_rect (start -0.94 0.47) (end 0.94 -0.47)
      (stroke (width 0.05) (type solid)) (fill none) (layer "B.CrtYd"))
    (fp_rect (start -0.499 0.249) (end 0.499 -0.249)
      (stroke (width 0.15) (type solid)) (fill none) (layer "B.Fab"))
    (pad "1" smd roundrect (at -0.484 0 180) (size 0.59 0.64) (layers "B.Cu" "B.Paste" "B.Mask") (roundrect_rratio 0.25)
      (net 17 "PS_1V8") (pintype "passive"))
    (pad "2" smd roundrect (at 0.484 0 180) (size 0.59 0.64) (layers "B.Cu" "B.Paste" "B.Mask") (roundrect_rratio 0.25)
      (net 1 "GND") (pintype "passive"))
  )
	(footprint "kria-k26-devboard-footprints:C_0402_1005Metric" (layer "B.Cu")
    (at 120.65 97.14 -90)
    (descr "Capacitor SMD 0402")
    (tags "capacitor SMD 0402")
    (property "Author" "Antmicro")
    (property "Dielectric" "")
    (property "License" "Apache-2.0")
    (property "MPN" "GRM155R61A475MEAAD")
    (property "Manufacturer" "Murata")
    (property "Sheetfile" "usb.kicad_sch")
    (property "Sheetname" "USB")
    (property "Val" "4u7")
    (property "Voltage" "")
    (property "ki_description" " ")
    (attr smd)
    (fp_text reference "C86" (at -1.154 1.479 90) (layer "B.SilkS")
        (effects (font (size 0.7 0.7) (thickness 0.15)) (justify left bottom mirror))
    )
    (fp_text value "C_4u7_0402" (at 0 -1.4 90) (layer "B.Fab") hide
        (effects (font (size 0.7 0.7) (thickness 0.15)) (justify left bottom mirror))
    )
    (fp_text user "Author: Antmicro" (at -0.932 -4.17 90) (layer "B.Fab") hide
        (effects (font (size 0.7 0.7) (thickness 0.15)) (justify left bottom mirror))
    )
    (fp_text user "${REFERENCE}" (at -0.932 -3.168 90) (layer "B.Fab") hide
        (effects (font (size 0.7 0.7) (thickness 0.15)) (justify left bottom mirror))
    )
    (fp_text user "License: Apache-2.0" (at -0.932 -5.17 90) (layer "B.Fab") hide
        (effects (font (size 0.7 0.7) (thickness 0.15)) (justify left bottom mirror))
    )
    (fp_rect (start -0.94 0.47) (end 0.94 -0.47)
      (stroke (width 0.05) (type solid)) (fill none) (layer "B.CrtYd"))
    (fp_rect (start -0.499 0.249) (end 0.499 -0.249)
      (stroke (width 0.15) (type solid)) (fill none) (layer "B.Fab"))
    (pad "1" smd roundrect (at -0.484 0 270) (size 0.59 0.64) (layers "B.Cu" "B.Paste" "B.Mask") (roundrect_rratio 0.25)
      (net 154 "Net-(U23-VDD_3V3)") (pintype "passive"))
    (pad "2" smd roundrect (at 0.484 0 270) (size 0.59 0.64) (layers "B.Cu" "B.Paste" "B.Mask") (roundrect_rratio 0.25)
      (net 1 "GND") (pintype "passive"))
  )
	(footprint "kria-k26-devboard-footprints:C_0402_1005Metric" (layer "B.Cu")
    (at 121.599 97.154 -90)
    (descr "Capacitor SMD 0402")
    (tags "capacitor SMD 0402")
    (property "Author" "Antmicro")
    (property "Dielectric" "X5R")
    (property "License" "Apache-2.0")
    (property "MPN" "GRM155R61H104KE14D")
    (property "Manufacturer" "Murata")
    (property "Sheetfile" "usb.kicad_sch")
    (property "Sheetname" "USB")
    (property "Val" "100n")
    (property "Voltage" "50V")
    (property "ki_description" " ")
    (attr smd)
    (fp_text reference "C89" (at -1.154 1.479 90) (layer "B.SilkS")
        (effects (font (size 0.7 0.7) (thickness 0.15)) (justify left bottom mirror))
    )
    (fp_text value "C_100n_0402" (at 0 -1.4 90) (layer "B.Fab") hide
        (effects (font (size 0.7 0.7) (thickness 0.15)) (justify left bottom mirror))
    )
    (fp_text user "Author: Antmicro" (at -0.932 -4.17 90) (layer "B.Fab") hide
        (effects (font (size 0.7 0.7) (thickness 0.15)) (justify left bottom mirror))
    )
    (fp_text user "License: Apache-2.0" (at -0.932 -5.17 90) (layer "B.Fab") hide
        (effects (font (size 0.7 0.7) (thickness 0.15)) (justify left bottom mirror))
    )
    (fp_text user "${REFERENCE}" (at -0.932 -3.168 90) (layer "B.Fab") hide
        (effects (font (size 0.7 0.7) (thickness 0.15)) (justify left bottom mirror))
    )
    (fp_rect (start -0.94 0.47) (end 0.94 -0.47)
      (stroke (width 0.05) (type solid)) (fill none) (layer "B.CrtYd"))
    (fp_rect (start -0.499 0.249) (end 0.499 -0.249)
      (stroke (width 0.15) (type solid)) (fill none) (layer "B.Fab"))
    (pad "1" smd roundrect (at -0.484 0 270) (size 0.59 0.64) (layers "B.Cu" "B.Paste" "B.Mask") (roundrect_rratio 0.25)
      (net 8 "SOM_5V0") (pintype "passive"))
    (pad "2" smd roundrect (at 0.484 0 270) (size 0.59 0.64) (layers "B.Cu" "B.Paste" "B.Mask") (roundrect_rratio 0.25)
      (net 1 "GND") (pintype "passive"))
  )
	(footprint "kria-k26-devboard-footprints:C_0805_2012Metric" (layer "B.Cu")
    (at 96.19 94.91)
    (descr "Capacitor SMD 0805")
    (tags "capacitor SMD 0805")
    (property "Author" "Antmicro")
    (property "Dielectric" "")
    (property "License" "Apache-2.0")
    (property "MPN" "C0805C476M9PACTU")
    (property "Manufacturer" "KEMET")
    (property "Sheetfile" "k26_som.kicad_sch")
    (property "Sheetname" "Xilinx K26 SOM")
    (property "Val" "47u")
    (property "Voltage" "")
    (property "ki_description" " ")
    (attr smd)
    (fp_text reference "C119" (at 4.695 0.435 180) (layer "B.SilkS")
        (effects (font (size 0.7 0.7) (thickness 0.15)) (justify left bottom mirror))
    )
    (fp_text value "C_47u_0805" (at 0 -1.947 180) (layer "B.Fab") hide
        (effects (font (size 0.7 0.7) (thickness 0.15)) (justify left bottom mirror))
    )
    (fp_text user "${REFERENCE}" (at -1.9 -3.947 180) (layer "B.Fab") hide
        (effects (font (size 0.7 0.7) (thickness 0.15)) (justify left bottom mirror))
    )
    (fp_text user "Author: Antmicro" (at -1.9 -5.947 180) (layer "B.Fab") hide
        (effects (font (size 0.7 0.7) (thickness 0.15)) (justify left bottom mirror))
    )
    (fp_text user "License: Apache-2.0" (at -1.9 -4.947 180) (layer "B.Fab") hide
        (effects (font (size 0.7 0.7) (thickness 0.15)) (justify left bottom mirror))
    )
    (fp_line (start -0.3 -0.8) (end 0.3 -0.8)
      (stroke (width 0.15) (type solid)) (layer "B.SilkS"))
    (fp_line (start -0.3 0.8) (end 0.3 0.8)
      (stroke (width 0.15) (type solid)) (layer "B.SilkS"))
    (fp_rect (start -1.9 0.93) (end 1.9 -0.93)
      (stroke (width 0.05) (type solid)) (fill none) (layer "B.CrtYd"))
    (fp_rect (start -0.95 0.675) (end 0.95 -0.675)
      (stroke (width 0.15) (type solid)) (fill none) (layer "B.Fab"))
    (pad "1" smd rect (at -1.05 0) (size 1.2 1.2) (layers "B.Cu" "B.Paste" "B.Mask")
      (net 8 "SOM_5V0") (pintype "passive"))
    (pad "2" smd rect (at 1.05 0) (size 1.2 1.2) (layers "B.Cu" "B.Paste" "B.Mask")
      (net 1 "GND") (pintype "passive"))
  )
	(footprint "kria-k26-devboard-footprints:C_0805_2012Metric" (layer "B.Cu")
    (at 96.215 96.785)
    (descr "Capacitor SMD 0805")
    (tags "capacitor SMD 0805")
    (property "Author" "Antmicro")
    (property "Dielectric" "")
    (property "License" "Apache-2.0")
    (property "MPN" "C0805C476M9PACTU")
    (property "Manufacturer" "KEMET")
    (property "Sheetfile" "k26_som.kicad_sch")
    (property "Sheetname" "Xilinx K26 SOM")
    (property "Val" "47u")
    (property "Voltage" "")
    (property "ki_description" " ")
    (attr smd)
    (fp_text reference "C120" (at 4.695 0.435 180) (layer "B.SilkS")
        (effects (font (size 0.7 0.7) (thickness 0.15)) (justify left bottom mirror))
    )
    (fp_text value "C_47u_0805" (at 0 -1.947 180) (layer "B.Fab") hide
        (effects (font (size 0.7 0.7) (thickness 0.15)) (justify left bottom mirror))
    )
    (fp_text user "${REFERENCE}" (at -1.9 -3.947 180) (layer "B.Fab") hide
        (effects (font (size 0.7 0.7) (thickness 0.15)) (justify left bottom mirror))
    )
    (fp_text user "Author: Antmicro" (at -1.9 -5.947 180) (layer "B.Fab") hide
        (effects (font (size 0.7 0.7) (thickness 0.15)) (justify left bottom mirror))
    )
    (fp_text user "License: Apache-2.0" (at -1.9 -4.947 180) (layer "B.Fab") hide
        (effects (font (size 0.7 0.7) (thickness 0.15)) (justify left bottom mirror))
    )
    (fp_line (start -0.3 -0.8) (end 0.3 -0.8)
      (stroke (width 0.15) (type solid)) (layer "B.SilkS"))
    (fp_line (start -0.3 0.8) (end 0.3 0.8)
      (stroke (width 0.15) (type solid)) (layer "B.SilkS"))
    (fp_rect (start -1.9 0.93) (end 1.9 -0.93)
      (stroke (width 0.05) (type solid)) (fill none) (layer "B.CrtYd"))
    (fp_rect (start -0.95 0.675) (end 0.95 -0.675)
      (stroke (width 0.15) (type solid)) (fill none) (layer "B.Fab"))
    (pad "1" smd rect (at -1.05 0) (size 1.2 1.2) (layers "B.Cu" "B.Paste" "B.Mask")
      (net 8 "SOM_5V0") (pintype "passive"))
    (pad "2" smd rect (at 1.05 0) (size 1.2 1.2) (layers "B.Cu" "B.Paste" "B.Mask")
      (net 1 "GND") (pintype "passive"))
  )
	(footprint "kria-k26-devboard-footprints:C_0402_1005Metric" (layer "B.Cu")
    (at 95.5 99.2)
    (descr "Capacitor SMD 0402")
    (tags "capacitor SMD 0402")
    (property "Author" "Antmicro")
    (property "Dielectric" "")
    (property "License" "Apache-2.0")
    (property "MPN" "C1005X6S1A105K050BC")
    (property "Manufacturer" "TDK")
    (property "Sheetfile" "k26_som.kicad_sch")
    (property "Sheetname" "Xilinx K26 SOM")
    (property "Val" "1u")
    (property "Voltage" "")
    (property "ki_description" " ")
    (attr smd)
    (fp_text reference "C121" (at 1.39 2.34 180) (layer "B.SilkS")
        (effects (font (size 0.7 0.7) (thickness 0.15)) (justify left bottom mirror))
    )
    (fp_text value "C_1u_0402" (at 0 -1.4 180) (layer "B.Fab") hide
        (effects (font (size 0.7 0.7) (thickness 0.15)) (justify left bottom mirror))
    )
    (fp_text user "License: Apache-2.0" (at -0.932 -5.17 180) (layer "B.Fab") hide
        (effects (font (size 0.7 0.7) (thickness 0.15)) (justify left bottom mirror))
    )
    (fp_text user "${REFERENCE}" (at -0.932 -3.168 180) (layer "B.Fab") hide
        (effects (font (size 0.7 0.7) (thickness 0.15)) (justify left bottom mirror))
    )
    (fp_text user "Author: Antmicro" (at -0.932 -4.17 180) (layer "B.Fab") hide
        (effects (font (size 0.7 0.7) (thickness 0.15)) (justify left bottom mirror))
    )
    (fp_rect (start -0.94 0.47) (end 0.94 -0.47)
      (stroke (width 0.05) (type solid)) (fill none) (layer "B.CrtYd"))
    (fp_rect (start -0.499 0.249) (end 0.499 -0.249)
      (stroke (width 0.15) (type solid)) (fill none) (layer "B.Fab"))
    (pad "1" smd roundrect (at -0.484 0) (size 0.59 0.64) (layers "B.Cu" "B.Paste" "B.Mask") (roundrect_rratio 0.25)
      (net 8 "SOM_5V0") (pintype "passive"))
    (pad "2" smd roundrect (at 0.484 0) (size 0.59 0.64) (layers "B.Cu" "B.Paste" "B.Mask") (roundrect_rratio 0.25)
      (net 1 "GND") (pintype "passive"))
  )
	(footprint "kria-k26-devboard-footprints:C_0402_1005Metric" (layer "B.Cu")
    (at 95.5 98.2)
    (descr "Capacitor SMD 0402")
    (tags "capacitor SMD 0402")
    (property "Author" "Antmicro")
    (property "Dielectric" "X5R")
    (property "License" "Apache-2.0")
    (property "MPN" "GRM155R61H104KE14D")
    (property "Manufacturer" "Murata")
    (property "Sheetfile" "k26_som.kicad_sch")
    (property "Sheetname" "Xilinx K26 SOM")
    (property "Val" "100n")
    (property "Voltage" "50V")
    (property "ki_description" " ")
    (attr smd)
    (fp_text reference "C122" (at 1.39 2.34 180) (layer "B.SilkS")
        (effects (font (size 0.7 0.7) (thickness 0.15)) (justify left bottom mirror))
    )
    (fp_text value "C_100n_0402" (at 0 -1.4 180) (layer "B.Fab") hide
        (effects (font (size 0.7 0.7) (thickness 0.15)) (justify left bottom mirror))
    )
    (fp_text user "${REFERENCE}" (at -0.932 -3.168 180) (layer "B.Fab") hide
        (effects (font (size 0.7 0.7) (thickness 0.15)) (justify left bottom mirror))
    )
    (fp_text user "License: Apache-2.0" (at -0.932 -5.17 180) (layer "B.Fab") hide
        (effects (font (size 0.7 0.7) (thickness 0.15)) (justify left bottom mirror))
    )
    (fp_text user "Author: Antmicro" (at -0.932 -4.17 180) (layer "B.Fab") hide
        (effects (font (size 0.7 0.7) (thickness 0.15)) (justify left bottom mirror))
    )
    (fp_rect (start -0.94 0.47) (end 0.94 -0.47)
      (stroke (width 0.05) (type solid)) (fill none) (layer "B.CrtYd"))
    (fp_rect (start -0.499 0.249) (end 0.499 -0.249)
      (stroke (width 0.15) (type solid)) (fill none) (layer "B.Fab"))
    (pad "1" smd roundrect (at -0.484 0) (size 0.59 0.64) (layers "B.Cu" "B.Paste" "B.Mask") (roundrect_rratio 0.25)
      (net 8 "SOM_5V0") (pintype "passive"))
    (pad "2" smd roundrect (at 0.484 0) (size 0.59 0.64) (layers "B.Cu" "B.Paste" "B.Mask") (roundrect_rratio 0.25)
      (net 1 "GND") (pintype "passive"))
  )
	(footprint "kria-k26-devboard-footprints:C_0402_1005Metric" (layer "B.Cu")
    (at 92.5 127.775)
    (descr "Capacitor SMD 0402")
    (tags "capacitor SMD 0402")
    (property "Author" "Antmicro")
    (property "Dielectric" "X5R")
    (property "License" "Apache-2.0")
    (property "MPN" "GRM155R61H104KE14D")
    (property "Manufacturer" "Murata")
    (property "Sheetfile" "k26_som.kicad_sch")
    (property "Sheetname" "Xilinx K26 SOM")
    (property "Val" "100n")
    (property "Voltage" "50V")
    (property "ki_description" " ")
    (attr smd)
    (fp_text reference "C129" (at 3.77 0.335 180) (layer "B.SilkS")
        (effects (font (size 0.7 0.7) (thickness 0.15)) (justify left bottom mirror))
    )
    (fp_text value "C_100n_0402" (at 0 -1.4 180) (layer "B.Fab") hide
        (effects (font (size 0.7 0.7) (thickness 0.15)) (justify left bottom mirror))
    )
    (fp_text user "License: Apache-2.0" (at -0.932 -5.17 180) (layer "B.Fab") hide
        (effects (font (size 0.7 0.7) (thickness 0.15)) (justify left bottom mirror))
    )
    (fp_text user "Author: Antmicro" (at -0.932 -4.17 180) (layer "B.Fab") hide
        (effects (font (size 0.7 0.7) (thickness 0.15)) (justify left bottom mirror))
    )
    (fp_text user "${REFERENCE}" (at -0.932 -3.168 180) (layer "B.Fab") hide
        (effects (font (size 0.7 0.7) (thickness 0.15)) (justify left bottom mirror))
    )
    (fp_rect (start -0.94 0.47) (end 0.94 -0.47)
      (stroke (width 0.05) (type solid)) (fill none) (layer "B.CrtYd"))
    (fp_rect (start -0.499 0.249) (end 0.499 -0.249)
      (stroke (width 0.15) (type solid)) (fill none) (layer "B.Fab"))
    (pad "1" smd roundrect (at -0.484 0) (size 0.59 0.64) (layers "B.Cu" "B.Paste" "B.Mask") (roundrect_rratio 0.25)
      (net 20 "PL_3V3") (pintype "passive"))
    (pad "2" smd roundrect (at 0.484 0) (size 0.59 0.64) (layers "B.Cu" "B.Paste" "B.Mask") (roundrect_rratio 0.25)
      (net 1 "GND") (pintype "passive"))
  )
	(footprint "kria-k26-devboard-footprints:C_0402_1005Metric" (layer "B.Cu")
    (at 77.7 129.4 180)
    (descr "Capacitor SMD 0402")
    (tags "capacitor SMD 0402")
    (property "Author" "Antmicro")
    (property "Dielectric" "X5R")
    (property "License" "Apache-2.0")
    (property "MPN" "GRM155R61H104KE14D")
    (property "Manufacturer" "Murata")
    (property "Sheetfile" "debug.kicad_sch")
    (property "Sheetname" "Debug and JTAG")
    (property "Val" "100n")
    (property "Voltage" "50V")
    (property "ki_description" " ")
    (attr smd)
    (fp_text reference "C161" (at -1.44 0.61) (layer "B.SilkS")
        (effects (font (size 0.7 0.7) (thickness 0.15)) (justify left bottom mirror))
    )
    (fp_text value "C_100n_0402" (at 0 -1.4) (layer "B.Fab") hide
        (effects (font (size 0.7 0.7) (thickness 0.15)) (justify left bottom mirror))
    )
    (fp_text user "Author: Antmicro" (at -0.932 -4.17) (layer "B.Fab") hide
        (effects (font (size 0.7 0.7) (thickness 0.15)) (justify left bottom mirror))
    )
    (fp_text user "License: Apache-2.0" (at -0.932 -5.17) (layer "B.Fab") hide
        (effects (font (size 0.7 0.7) (thickness 0.15)) (justify left bottom mirror))
    )
    (fp_text user "${REFERENCE}" (at -0.932 -3.168) (layer "B.Fab") hide
        (effects (font (size 0.7 0.7) (thickness 0.15)) (justify left bottom mirror))
    )
    (fp_rect (start -0.94 0.47) (end 0.94 -0.47)
      (stroke (width 0.05) (type solid)) (fill none) (layer "B.CrtYd"))
    (fp_rect (start -0.499 0.249) (end 0.499 -0.249)
      (stroke (width 0.15) (type solid)) (fill none) (layer "B.Fab"))
    (pad "1" smd roundrect (at -0.484 0 180) (size 0.59 0.64) (layers "B.Cu" "B.Paste" "B.Mask") (roundrect_rratio 0.25)
      (net 17 "PS_1V8") (pintype "passive"))
    (pad "2" smd roundrect (at 0.484 0 180) (size 0.59 0.64) (layers "B.Cu" "B.Paste" "B.Mask") (roundrect_rratio 0.25)
      (net 1 "GND") (pintype "passive"))
  )
)
